# S9S_MB_2U (Grand Teton) — schematic netlist excerpt (pin names and nets, part order shuffled) for the footprints in the layout excerpt that follows; sources: Cadence DE-HDL packaged netlist, KiCad conversion of 03242023_DA0F0TMBIJ0_F0T_Motherboard_J_brd_V01_OCP.brd

C766  Q_CAP_DIFFBUS  DIFF BUS_0.22UF 6.3V 20% X6S  pkg C0201  page 176 : \1\ = P5E_CPU1_PE2_TX_C_DN<3> ; \2\ = P5E_CPU1_PE2_TX_DN<3>
R4078  Q_RES  10K 1% EMPTY  pkg 0402LF  page 212 : A = P3V3_AUX ; B = FG_SS_EN
PR835  Q_RES  0 5% CHIP  pkg 0402LF  page 259 : A = SW_P3V3_AUX_BOOT ; B = SW_P3V3_AUX_BOOT_R

(kicad_pcb
	(version 20260206)
	(generator "pcbnew")
	(generator_version "10.0")
	(general
		(thickness 1.6)
		(legacy_teardrops no)
	)
	(paper "A4")
	(title_block
		(title "03242023_DA0F0TMBIJ0_F0T_Motherboard_J_brd_V01_OCP.brd")
		(comment 1 "Grand Teton / footprints 2208-2210 of 6105")
	)
	(layers
		(0 "F.Cu" signal "TOP")
		(4 "In1.Cu" signal "GND")
		(6 "In2.Cu" signal "IN1")
		(8 "In3.Cu" signal "GND1")
		(10 "In4.Cu" signal "IN2")
		(12 "In5.Cu" signal "GND2")
		(14 "In6.Cu" signal "IN3")
		(16 "In7.Cu" signal "GND3")
		(18 "In8.Cu" signal "VCC")
		(20 "In9.Cu" signal "VCC1")
		(22 "In10.Cu" signal "GND4")
		(24 "In11.Cu" signal "IN4")
		(26 "In12.Cu" signal "GND5")
		(28 "In13.Cu" signal "IN5")
		(30 "In14.Cu" signal "GND6")
		(32 "In15.Cu" signal "IN6")
		(34 "In16.Cu" signal "GND7")
		(2 "B.Cu" signal "BOTTOM")
		(9 "F.Adhes" user "F.Adhesive")
		(11 "B.Adhes" user "B.Adhesive")
		(13 "F.Paste" user "Package Geometry/Pastemask Top")
		(15 "B.Paste" user "Package Geometry/Pastemask Bottom")
		(5 "F.SilkS" user "Ref Des/Silkscreen Top")
		(7 "B.SilkS" user "Ref Des/Silkscreen Bottom")
		(1 "F.Mask" user "Board Geometry/Soldermask Top")
		(3 "B.Mask" user "Board Geometry/Soldermask Bottom")
		(17 "Dwgs.User" user "User.Drawings")
		(19 "Cmts.User" user "User.Comments")
		(21 "Eco1.User" user "User.Eco1")
		(23 "Eco2.User" user "User.Eco2")
		(25 "Edge.Cuts" user "Board Geometry/Outline")
		(27 "Margin" user)
		(31 "F.CrtYd" user "Package Geometry/Place Bound Top")
		(29 "B.CrtYd" user "Package Geometry/Place Bound Bottom")
		(35 "F.Fab" user "Ref Des/Assembly Top")
		(33 "B.Fab" user "Ref Des/Assembly Bottom")
	)
	(footprint ""
		(layer "F.Cu")
		(at 452.486522 -75.093322)
		(property "Reference" "PR835"
			(at 0 0 0)
			(layer "F.SilkS")
			(hide yes)
			(effects
				(font
					(size 1.27 1.27)
				)
			)
		)
		(property "Value" ""
			(at 0 0 0)
			(layer "F.Fab")
			(effects
				(font
					(size 1.27 1.27)
				)
			)
		)
		(duplicate_pad_numbers_are_jumpers no)
		(fp_line
			(start -0.7874 -0.4064)
			(end 0.7874 -0.4064)
			(stroke
				(width 0.1524)
				(type default)
			)
			(layer "F.SilkS")
		)
		(fp_line
			(start -0.7874 0.4064)
			(end -0.7874 -0.4064)
			(stroke
				(width 0.1524)
				(type default)
			)
			(layer "F.SilkS")
		)
		(fp_line
			(start 0.7874 -0.4064)
			(end 0.7874 0.4064)
			(stroke
				(width 0.1524)
				(type default)
			)
			(layer "F.SilkS")
		)
		(fp_line
			(start 0.7874 0.4064)
			(end -0.7874 0.4064)
			(stroke
				(width 0.1524)
				(type default)
			)
			(layer "F.SilkS")
		)
		(fp_line
			(start -0.67945 -0.305054)
			(end -0.12065 -0.305054)
			(stroke
				(width 0.1)
				(type default)
			)
			(layer "F.Fab")
		)
		(fp_line
			(start -0.67945 0.3048)
			(end -0.67945 -0.305054)
			(stroke
				(width 0.1)
				(type default)
			)
			(layer "F.Fab")
		)
		(fp_line
			(start -0.12065 -0.305054)
			(end -0.12065 -0.2794)
			(stroke
				(width 0.1)
				(type default)
			)
			(layer "F.Fab")
		)
		(fp_line
			(start -0.12065 -0.2794)
			(end 0.12065 -0.2794)
			(stroke
				(width 0.1)
				(type default)
			)
			(layer "F.Fab")
		)
		(fp_line
			(start -0.12065 0.2794)
			(end -0.12065 0.3048)
			(stroke
				(width 0.1)
				(type default)
			)
			(layer "F.Fab")
		)
		(fp_line
			(start -0.12065 0.3048)
			(end -0.67945 0.3048)
			(stroke
				(width 0.1)
				(type default)
			)
			(layer "F.Fab")
		)
		(fp_line
			(start 0.120396 0.2794)
			(end -0.12065 0.2794)
			(stroke
				(width 0.1)
				(type default)
			)
			(layer "F.Fab")
		)
		(fp_line
			(start 0.120396 0.3048)
			(end 0.120396 0.2794)
			(stroke
				(width 0.1)
				(type default)
			)
			(layer "F.Fab")
		)
		(fp_line
			(start 0.12065 -0.3048)
			(end 0.67945 -0.3048)
			(stroke
				(width 0.1)
				(type default)
			)
			(layer "F.Fab")
		)
		(fp_line
			(start 0.12065 -0.2794)
			(end 0.12065 -0.3048)
			(stroke
				(width 0.1)
				(type default)
			)
			(layer "F.Fab")
		)
		(fp_line
			(start 0.67945 -0.3048)
			(end 0.67945 0.3048)
			(stroke
				(width 0.1)
				(type default)
			)
			(layer "F.Fab")
		)
		(fp_line
			(start 0.67945 0.3048)
			(end 0.120396 0.3048)
			(stroke
				(width 0.1)
				(type default)
			)
			(layer "F.Fab")
		)
		(pad "1" smd circle
			(at -0.40005 0)
			(size 0 0)
			(layers "F.Cu" "F.Mask" "F.Paste")
			(net "SW_P3V3_AUX_BOOT")
		)
		(pad "2" smd circle
			(at 0.40005 0)
			(size 0 0)
			(layers "F.Cu" "F.Mask" "F.Paste")
			(net "SW_P3V3_AUX_BOOT_R")
		)
	)
	(footprint ""
		(layer "F.Cu")
		(at 157.802834 -402.371052 -90)
		(property "Reference" "C766"
			(at 0 0 270)
			(layer "F.SilkS")
			(hide yes)
			(effects
				(font
					(size 1.27 1.27)
				)
			)
		)
		(property "Value" ""
			(at 0 0 270)
			(layer "F.Fab")
			(effects
				(font
					(size 1.27 1.27)
				)
			)
		)
		(duplicate_pad_numbers_are_jumpers no)
		(fp_line
			(start -0.299974 0.150114)
			(end -0.299974 -0.150114)
			(stroke
				(width 0.1)
				(type default)
			)
			(layer "F.Fab")
		)
		(fp_line
			(start 0.299974 0.150114)
			(end -0.299974 0.150114)
			(stroke
				(width 0.1)
				(type default)
			)
			(layer "F.Fab")
		)
		(fp_line
			(start -0.299974 -0.150114)
			(end 0.299974 -0.150114)
			(stroke
				(width 0.1)
				(type default)
			)
			(layer "F.Fab")
		)
		(fp_line
			(start 0.299974 -0.150114)
			(end 0.299974 0.150114)
			(stroke
				(width 0.1)
				(type default)
			)
			(layer "F.Fab")
		)
		(pad "1" smd rect
			(at -0.2667 0 270)
			(size 0.3048 0.381)
			(layers "F.Cu" "F.Mask" "F.Paste")
			(net "P5E_CPU1_PE2_TX_C_DN<3>")
		)
		(pad "2" smd rect
			(at 0.2667 0 270)
			(size 0.3048 0.381)
			(layers "F.Cu" "F.Mask" "F.Paste")
			(net "P5E_CPU1_PE2_TX_DN<3>")
		)
	)
	(footprint ""
		(layer "F.Cu")
		(at 235.413042 -245.402608 90)
		(property "Reference" "R4078"
			(at 0 0 90)
			(layer "F.SilkS")
			(hide yes)
			(effects
				(font
					(size 1.27 1.27)
				)
			)
		)
		(property "Value" ""
			(at 0 0 90)
			(layer "F.Fab")
			(effects
				(font
					(size 1.27 1.27)
				)
			)
		)
		(duplicate_pad_numbers_are_jumpers no)
		(fp_line
			(start 0.7874 -0.4064)
			(end 0.7874 0.4064)
			(stroke
				(width 0.1524)
				(type default)
			)
			(layer "F.SilkS")
		)
		(fp_line
			(start -0.7874 -0.4064)
			(end 0.7874 -0.4064)
			(stroke
				(width 0.1524)
				(type default)
			)
			(layer "F.SilkS")
		)
		(fp_line
			(start 0.7874 0.4064)
			(end -0.7874 0.4064)
			(stroke
				(width 0.1524)
				(type default)
			)
			(layer "F.SilkS")
		)
		(fp_line
			(start -0.7874 0.4064)
			(end -0.7874 -0.4064)
			(stroke
				(width 0.1524)
				(type default)
			)
			(layer "F.SilkS")
		)
		(fp_line
			(start -0.12065 -0.305054)
			(end -0.12065 -0.2794)
			(stroke
				(width 0.1)
				(type default)
			)
			(layer "F.Fab")
		)
		(fp_line
			(start -0.67945 -0.305054)
			(end -0.12065 -0.305054)
			(stroke
				(width 0.1)
				(type default)
			)
			(layer "F.Fab")
		)
		(fp_line
			(start 0.67945 -0.3048)
			(end 0.67945 0.3048)
			(stroke
				(width 0.1)
				(type default)
			)
			(layer "F.Fab")
		)
		(fp_line
			(start 0.12065 -0.3048)
			(end 0.67945 -0.3048)
			(stroke
				(width 0.1)
				(type default)
			)
			(layer "F.Fab")
		)
		(fp_line
			(start 0.12065 -0.2794)
			(end 0.12065 -0.3048)
			(stroke
				(width 0.1)
				(type default)
			)
			(layer "F.Fab")
		)
		(fp_line
			(start -0.12065 -0.2794)
			(end 0.12065 -0.2794)
			(stroke
				(width 0.1)
				(type default)
			)
			(layer "F.Fab")
		)
		(fp_line
			(start 0.120396 0.2794)
			(end -0.12065 0.2794)
			(stroke
				(width 0.1)
				(type default)
			)
			(layer "F.Fab")
		)
		(fp_line
			(start -0.12065 0.2794)
			(end -0.12065 0.3048)
			(stroke
				(width 0.1)
				(type default)
			)
			(layer "F.Fab")
		)
		(fp_line
			(start 0.67945 0.3048)
			(end 0.120396 0.3048)
			(stroke
				(width 0.1)
				(type default)
			)
			(layer "F.Fab")
		)
		(fp_line
			(start 0.120396 0.3048)
			(end 0.120396 0.2794)
			(stroke
				(width 0.1)
				(type default)
			)
			(layer "F.Fab")
		)
		(fp_line
			(start -0.12065 0.3048)
			(end -0.67945 0.3048)
			(stroke
				(width 0.1)
				(type default)
			)
			(layer "F.Fab")
		)
		(fp_line
			(start -0.67945 0.3048)
			(end -0.67945 -0.305054)
			(stroke
				(width 0.1)
				(type default)
			)
			(layer "F.Fab")
		)
		(pad "1" smd circle
			(at -0.40005 0 90)
			(size 0 0)
			(layers "F.Cu" "F.Mask" "F.Paste")
			(net "P3V3_AUX")
		)
		(pad "2" smd circle
			(at 0.40005 0 90)
			(size 0 0)
			(layers "F.Cu" "F.Mask" "F.Paste")
			(net "FG_SS_EN")
		)
	)
)
